(kicad_pcb
	(version 20260206)
	(generator "pcbnew")
	(generator_version "10.0")
	(general
		(thickness 1.21888)
		(legacy_teardrops no)
	)
	(paper "A4")
	(title_block
		(title "timecard-v9 — TimeCard-DC-V9_EXP.PcbDoc")
		(comment 1 "Time Appliance Project (Time Card) / footprints 125-130 of 402")
	)
	(layers
		(0 "F.Cu" signal "TOP")
		(4 "In1.Cu" signal "SGND")
		(6 "In2.Cu" signal "IN1")
		(8 "In3.Cu" signal "IN2")
		(10 "In4.Cu" signal "SGND1")
		(2 "B.Cu" signal "BOTTOM")
		(9 "F.Adhes" user "F.Adhesive")
		(11 "B.Adhes" user "B.Adhesive")
		(13 "F.Paste" user "Top Paste")
		(15 "B.Paste" user "Bottom Paste")
		(5 "F.SilkS" user "Top Overlay")
		(7 "B.SilkS" user "Bottom Overlay")
		(1 "F.Mask" user "Top Solder")
		(3 "B.Mask" user "Bottom Solder")
		(17 "Dwgs.User" user "User.Drawings")
		(19 "Cmts.User" user "User.Comments")
		(21 "Eco1.User" user "User.Eco1")
		(23 "Eco2.User" user "User.Eco2")
		(25 "Edge.Cuts" user)
		(27 "Margin" user)
		(31 "F.CrtYd" user "Top Courtyard")
		(29 "B.CrtYd" user "Bottom Courtyard")
		(35 "F.Fab" user "Top Component Center")
		(33 "B.Fab" user "Bottom Component Center")
	)
	(footprint "Vault:FP-RUT0012A-MFG"
		(layer "F.Cu")
		(at 194.1216 122.6162)
		(property "Reference" "U30"
			(at -2.160579 -2.3157 90)
			(unlocked yes)
			(layer "F.SilkS")
			(effects
				(font
					(size 0.762 0.762)
					(thickness 0.2032)
				)
			)
		)
		(property "Value" "TMUX1072RUTR"
			(at 7.401265 3.164071 0)
			(unlocked yes)
			(layer "F.SilkS")
			(hide yes)
			(effects
				(font
					(size 0.762 0.762)
					(thickness 0.2032)
				)
			)
		)
		(sheetname "11-M2_RCB_MUX")
		(sheetfile "11-M2_RCB_MUX.kicad_sch")
		(duplicate_pad_numbers_are_jumpers no)
		(fp_line
			(start -0.9 -1.525)
			(end 0.9 -1.525)
			(stroke
				(width 0.2)
				(type solid)
			)
			(layer "F.SilkS")
		)
		(fp_line
			(start -0.9 1.525)
			(end 0.9 1.525)
			(stroke
				(width 0.2)
				(type solid)
			)
			(layer "F.SilkS")
		)
		(fp_circle
			(center -1.575 -0.8)
			(end -1.575 -0.925)
			(stroke
				(width 0.25)
				(type solid)
			)
			(fill no)
			(layer "F.SilkS")
		)
		(fp_rect
			(start -0.85 -0.3)
			(end -0.35 -0.5)
			(stroke
				(width 0)
				(type default)
			)
			(fill yes)
			(layer "F.Paste")
		)
		(fp_rect
			(start -0.85 0.1)
			(end -0.35 -0.1)
			(stroke
				(width 0)
				(type default)
			)
			(fill yes)
			(layer "F.Paste")
		)
		(fp_rect
			(start -0.85 0.5)
			(end -0.35 0.3)
			(stroke
				(width 0)
				(type default)
			)
			(fill yes)
			(layer "F.Paste")
		)
		(fp_rect
			(start -0.85 0.9)
			(end -0.35 0.7)
			(stroke
				(width 0)
				(type default)
			)
			(fill yes)
			(layer "F.Paste")
		)
		(fp_rect
			(start -0.1 -0.5)
			(end 0.1 -1)
			(stroke
				(width 0)
				(type default)
			)
			(fill yes)
			(layer "F.Paste")
		)
		(fp_rect
			(start -0.1 1)
			(end 0.1 0.5)
			(stroke
				(width 0)
				(type default)
			)
			(fill yes)
			(layer "F.Paste")
		)
		(fp_rect
			(start 0.35 -0.7)
			(end 0.85 -0.9)
			(stroke
				(width 0)
				(type default)
			)
			(fill yes)
			(layer "F.Paste")
		)
		(fp_rect
			(start 0.35 -0.3)
			(end 0.85 -0.5)
			(stroke
				(width 0)
				(type default)
			)
			(fill yes)
			(layer "F.Paste")
		)
		(fp_rect
			(start 0.35 0.1)
			(end 0.85 -0.1)
			(stroke
				(width 0)
				(type default)
			)
			(fill yes)
			(layer "F.Paste")
		)
		(fp_rect
			(start 0.35 0.5)
			(end 0.85 0.3)
			(stroke
				(width 0)
				(type default)
			)
			(fill yes)
			(layer "F.Paste")
		)
		(fp_rect
			(start 0.35 0.9)
			(end 0.85 0.7)
			(stroke
				(width 0)
				(type default)
			)
			(fill yes)
			(layer "F.Paste")
		)
		(fp_poly
			(pts
				(xy -0.5 -1) (xy -0.35 -1) (xy -0.35 -0.7) (xy -0.85 -0.7) (xy -0.85 -0.9) (xy -0.5 -0.9)
			)
			(stroke
				(width 0)
				(type default)
			)
			(fill yes)
			(layer "F.Paste")
		)
		(fp_line
			(start -1.05 -1.2)
			(end 1.05 -1.2)
			(stroke
				(width 0.2)
				(type solid)
			)
			(layer "F.CrtYd")
		)
		(fp_line
			(start -1.05 1.2)
			(end -1.05 -1.2)
			(stroke
				(width 0.2)
				(type solid)
			)
			(layer "F.CrtYd")
		)
		(fp_line
			(start -1.05 1.2)
			(end 1.05 1.2)
			(stroke
				(width 0.2)
				(type solid)
			)
			(layer "F.CrtYd")
		)
		(fp_line
			(start 1.05 1.2)
			(end 1.05 -1.2)
			(stroke
				(width 0.2)
				(type solid)
			)
			(layer "F.CrtYd")
		)
		(fp_line
			(start -1.05 -1.2)
			(end 1.05 -1.2)
			(stroke
				(width 0.2)
				(type solid)
			)
			(layer "F.Fab")
		)
		(fp_line
			(start -1.05 1.2)
			(end -1.05 -1.2)
			(stroke
				(width 0.2)
				(type solid)
			)
			(layer "F.Fab")
		)
		(fp_line
			(start -1.05 1.2)
			(end 1.05 1.2)
			(stroke
				(width 0.2)
				(type solid)
			)
			(layer "F.Fab")
		)
		(fp_line
			(start -0.5 0)
			(end 0.5 0)
			(stroke
				(width 0.1)
				(type solid)
			)
			(layer "F.Fab")
		)
		(fp_line
			(start 0 0.5)
			(end 0 -0.5)
			(stroke
				(width 0.1)
				(type solid)
			)
			(layer "F.Fab")
		)
		(fp_line
			(start 1.05 1.2)
			(end 1.05 -1.2)
			(stroke
				(width 0.2)
				(type solid)
			)
			(layer "F.Fab")
		)
		(fp_text user "${REFERENCE}"
			(at -0.00001 0.09602 0)
			(unlocked yes)
			(layer "F.Fab")
			(effects
				(font
					(face "Arial")
					(size 0.63 0.63)
					(thickness 0.1)
				)
				(justify left bottom)
			)
		)
		(pad "" smd custom
			(at -0.5 -1.1)
			(size 0.000001 0.000001)
			(layers "F.Cu" "F.Mask")
			(solder_mask_margin 0)
			(thermal_bridge_angle 90)
			(options
				(clearance outline)
				(anchor circle)
			)
			(primitives
				(gr_poly
					(pts
						(xy 0 0) (xy 0.15 0) (xy 0.15 0.4) (xy -0.45 0.4) (xy -0.45 0.2) (xy 0 0.2)
					)
					(width 0)
					(fill yes)
				)
			)
		)
		(pad "1" smd circle
			(at -0.45 -0.8)
			(size 0.18 0.18)
			(layers "F.Cu" "F.Mask" "F.Paste")
			(net "DIP_SW_GPS2_SEL")
			(solder_mask_margin 0)
			(solder_paste_margin -1000)
			(thermal_bridge_angle 90)
		)
		(pad "2" smd rect
			(at -0.65 -0.4)
			(size 0.6 0.2)
			(layers "F.Cu" "F.Mask" "F.Paste")
			(net "M2_GPS2_PIN11")
			(solder_mask_margin 0)
			(solder_paste_margin -1000)
		)
		(pad "3" smd rect
			(at -0.65 0)
			(size 0.6 0.2)
			(layers "F.Cu" "F.Mask" "F.Paste")
			(net "GND")
			(solder_mask_margin 0)
			(solder_paste_margin -1000)
		)
		(pad "4" smd rect
			(at -0.65 0.4)
			(size 0.6 0.2)
			(layers "F.Cu" "F.Mask" "F.Paste")
			(net "M2_GPS2_PIN12")
			(solder_mask_margin 0)
			(solder_paste_margin -1000)
		)
		(pad "5" smd rect
			(at -0.65 0.8)
			(size 0.6 0.2)
			(layers "F.Cu" "F.Mask" "F.Paste")
			(net "DIP_SW_GPS2_SEL")
			(solder_mask_margin 0)
			(solder_paste_margin -1000)
		)
		(pad "6" smd rect
			(at 0 0.8)
			(size 0.2 0.6)
			(layers "F.Cu" "F.Mask" "F.Paste")
			(net "GND")
			(solder_mask_margin 0)
			(solder_paste_margin -1000)
		)
		(pad "7" smd rect
			(at 0.65 0.8)
			(size 0.6 0.2)
			(layers "F.Cu" "F.Mask" "F.Paste")
			(net "NetR175_1")
			(solder_mask_margin 0)
			(solder_paste_margin -1000)
		)
		(pad "8" smd rect
			(at 0.65 0.4)
			(size 0.6 0.2)
			(layers "F.Cu" "F.Mask" "F.Paste")
			(net "RCB_GPS2_PIN12")
			(solder_mask_margin 0)
			(solder_paste_margin -1000)
		)
		(pad "9" smd rect
			(at 0.65 0)
			(size 0.6 0.2)
			(layers "F.Cu" "F.Mask" "F.Paste")
			(net "+3.3V")
			(solder_mask_margin 0)
			(solder_paste_margin -1000)
		)
		(pad "10" smd rect
			(at 0.65 -0.4)
			(size 0.6 0.2)
			(layers "F.Cu" "F.Mask" "F.Paste")
			(net "RCB_GPS2_PIN11")
			(solder_mask_margin 0)
			(solder_paste_margin -1000)
		)
		(pad "11" smd rect
			(at 0.65 -0.8)
			(size 0.6 0.2)
			(layers "F.Cu" "F.Mask" "F.Paste")
			(net "NetR171_1")
			(solder_mask_margin 0)
			(solder_paste_margin -1000)
		)
		(pad "12" smd rect
			(at 0 -0.8)
			(size 0.2 0.6)
			(layers "F.Cu" "F.Mask" "F.Paste")
			(net "GND")
			(solder_mask_margin 0)
			(solder_paste_margin -1000)
		)
	)
	(footprint "Passives:FUSM1608X60N"
		(layer "F.Cu")
		(at 222.1216 64.8162 -90)
		(property "Reference" "F1"
			(at 0.6 0.706655 90)
			(unlocked yes)
			(layer "F.SilkS")
			(effects
				(font
					(size 0.762 0.762)
					(thickness 0.2286)
				)
				(justify left bottom)
			)
		)
		(property "Value" "FUSE_0603_5.00A"
			(at 4.987045 2.1929 0)
			(unlocked yes)
			(layer "F.SilkS")
			(hide yes)
			(effects
				(font
					(size 0.762 0.762)
					(thickness 0.2286)
				)
				(justify left bottom)
			)
		)
		(sheetname "03-POWER")
		(sheetfile "03-POWER.kicad_sch")
		(duplicate_pad_numbers_are_jumpers no)
		(fp_line
			(start 0 0.5)
			(end 0 -0.5)
			(stroke
				(width 0.1524)
				(type solid)
			)
			(layer "F.SilkS")
		)
		(pad "1" smd rect
			(at -0.69 0)
			(size 1 0.72)
			(layers "F.Cu" "F.Mask" "F.Paste")
			(net "NetCR1_2")
		)
		(pad "2" smd rect
			(at 0.69 0)
			(size 1 0.72)
			(layers "F.Cu" "F.Mask" "F.Paste")
			(net "+12V_SENS")
		)
	)
	(footprint "Vault:FP-5TS1-IPC_C"
		(layer "F.Cu")
		(at 180.90984 105.1162 -90)
		(property "Reference" "U7"
			(at -2.735479 -0.228605 0)
			(unlocked yes)
			(layer "F.SilkS")
			(effects
				(font
					(size 0.762 0.762)
					(thickness 0.2286)
				)
			)
		)
		(property "Value" "AT24MAC402-STUM-T"
			(at 10.727395 3.189471 270)
			(unlocked yes)
			(layer "F.SilkS")
			(hide yes)
			(effects
				(font
					(size 0.762 0.762)
					(thickness 0.2286)
				)
			)
		)
		(sheetname "05-GPS_IMU_SENSORS")
		(sheetfile "05-GPS_IMU_SENSORS.kicad_sch")
		(duplicate_pad_numbers_are_jumpers no)
		(fp_line
			(start 0.17207 1.44999)
			(end -0.17207 1.44999)
			(stroke
				(width 0.2)
				(type solid)
			)
			(layer "F.SilkS")
		)
		(fp_line
			(start 0.8 0.30893)
			(end 0.8 -0.30894)
			(stroke
				(width 0.2)
				(type solid)
			)
			(layer "F.SilkS")
		)
		(fp_line
			(start 0.17207 -1.45)
			(end -0.17207 -1.45)
			(stroke
				(width 0.2)
				(type solid)
			)
			(layer "F.SilkS")
		)
		(fp_circle
			(center -2.21036 -0.95001)
			(end -2.33536 -0.95001)
			(stroke
				(width 0.25)
				(type solid)
			)
			(fill no)
			(layer "F.SilkS")
		)
		(fp_line
			(start -1.68536 1.54999)
			(end -1.68536 -1.55)
			(stroke
				(width 0.2)
				(type solid)
			)
			(layer "F.CrtYd")
		)
		(fp_line
			(start 1.68535 1.54999)
			(end -1.68536 1.54999)
			(stroke
				(width 0.2)
				(type solid)
			)
			(layer "F.CrtYd")
		)
		(fp_line
			(start 1.68535 1.54999)
			(end 1.68535 -1.55)
			(stroke
				(width 0.2)
				(type solid)
			)
			(layer "F.CrtYd")
		)
		(fp_line
			(start 1.68535 -1.55)
			(end -1.68536 -1.55)
			(stroke
				(width 0.2)
				(type solid)
			)
			(layer "F.CrtYd")
		)
		(fp_line
			(start -1.68536 1.54999)
			(end -1.68536 -1.55)
			(stroke
				(width 0.2)
				(type solid)
			)
			(layer "F.Fab")
		)
		(fp_line
			(start 1.68535 1.54999)
			(end -1.68536 1.54999)
			(stroke
				(width 0.2)
				(type solid)
			)
			(layer "F.Fab")
		)
		(fp_line
			(start 1.68535 1.54999)
			(end 1.68535 -1.55)
			(stroke
				(width 0.2)
				(type solid)
			)
			(layer "F.Fab")
		)
		(fp_line
			(start 0 0.49999)
			(end 0 -0.5)
			(stroke
				(width 0.1)
				(type solid)
			)
			(layer "F.Fab")
		)
		(fp_line
			(start 0.5 0)
			(end -0.5 0)
			(stroke
				(width 0.1)
				(type solid)
			)
			(layer "F.Fab")
		)
		(fp_line
			(start 1.68535 -1.55)
			(end -1.68536 -1.55)
			(stroke
				(width 0.2)
				(type solid)
			)
			(layer "F.Fab")
		)
		(fp_text user "${REFERENCE}"
			(at 0 0.28424 270)
			(unlocked yes)
			(layer "F.Fab")
			(effects
				(font
					(face "Arial")
					(size 0.63 0.63)
					(thickness 0.1)
				)
				(justify left bottom)
			)
		)
		(pad "1" smd rect
			(at -1.06621 -0.95001 270)
			(size 1.03828 0.53213)
			(layers "F.Cu" "F.Mask" "F.Paste")
			(net "SCL")
			(solder_mask_margin 0)
			(solder_paste_margin 0)
		)
		(pad "2" smd roundrect
			(at -1.06621 0 270)
			(size 1.03828 0.53213)
			(layers "F.Cu" "F.Mask" "F.Paste")
			(roundrect_rratio 0.5)
			(net "GND")
			(solder_mask_margin 0)
			(solder_paste_margin 0)
		)
		(pad "3" smd roundrect
			(at -1.06621 0.95 270)
			(size 1.03828 0.53213)
			(layers "F.Cu" "F.Mask" "F.Paste")
			(roundrect_rratio 0.5)
			(net "SDA")
			(solder_mask_margin 0)
			(solder_paste_margin 0)
		)
		(pad "4" smd roundrect
			(at 1.06621 0.95 270)
			(size 1.03828 0.53213)
			(layers "F.Cu" "F.Mask" "F.Paste")
			(roundrect_rratio 0.5)
			(net "+3.3V")
			(solder_mask_margin 0)
			(solder_paste_margin 0)
		)
		(pad "5" smd roundrect
			(at 1.06621 -0.95001 270)
			(size 1.03828 0.53213)
			(layers "F.Cu" "F.Mask" "F.Paste")
			(roundrect_rratio 0.5)
			(net "EXT_EEPROM_WP")
			(solder_mask_margin 0)
			(solder_paste_margin 0)
		)
	)
	(footprint "Vault:RESC1005X40X25NL05T05"
		(layer "F.Cu")
		(at 194.9216 128.7162 90)
		(property "Reference" "R153"
			(at 1.373069 -0.0968 0)
			(unlocked yes)
			(layer "F.SilkS")
			(effects
				(font
					(size 0.762 0.762)
					(thickness 0.2032)
				)
			)
		)
		(property "Value" "DNI_27_1%_0402"
			(at -2.732271 10.270975 0)
			(unlocked yes)
			(layer "F.SilkS")
			(hide yes)
			(effects
				(font
					(size 0.762 0.762)
					(thickness 0.2032)
				)
			)
		)
		(sheetname "11-M2_RCB_MUX")
		(sheetfile "11-M2_RCB_MUX.kicad_sch")
		(duplicate_pad_numbers_are_jumpers no)
		(pad "1" smd rect
			(at -0.45 0 180)
			(size 0.55 0.55)
			(layers "F.Cu" "F.Mask" "F.Paste")
			(net "RCB_GPS2_TP2")
		)
		(pad "2" smd rect
			(at 0.45 0 180)
			(size 0.55 0.55)
			(layers "F.Cu" "F.Mask" "F.Paste")
			(net "GPS2_TP2")
		)
	)
	(footprint "Vault:RESC1005X40X25NL05T05"
		(layer "F.Cu")
		(at 195.7216 135.8162)
		(property "Reference" "R158"
			(at 1.6032 0.926921 0)
			(unlocked yes)
			(layer "F.SilkS")
			(effects
				(font
					(size 0.762 0.762)
					(thickness 0.2032)
				)
			)
		)
		(property "Value" "DNI_27_1%_0402"
			(at -2.732271 10.270975 270)
			(unlocked yes)
			(layer "F.SilkS")
			(hide yes)
			(effects
				(font
					(size 0.762 0.762)
					(thickness 0.2032)
				)
			)
		)
		(sheetname "11-M2_RCB_MUX")
		(sheetfile "11-M2_RCB_MUX.kicad_sch")
		(duplicate_pad_numbers_are_jumpers no)
		(pad "1" smd rect
			(at -0.45 0 90)
			(size 0.55 0.55)
			(layers "F.Cu" "F.Mask" "F.Paste")
			(net "M2_GPS2_TP1")
		)
		(pad "2" smd rect
			(at 0.45 0 90)
			(size 0.55 0.55)
			(layers "F.Cu" "F.Mask" "F.Paste")
			(net "GPS2_TP1")
		)
	)
	(footprint "Vault:FP-0402-L_1_0_1-W_0_5_0_1-IPC_C"
		(layer "F.Cu")
		(at 73.9216 143.8162 180)
		(property "Reference" "C28"
			(at 0.2286 -1.473069 180)
			(unlocked yes)
			(layer "F.SilkS")
			(effects
				(font
					(size 0.762 0.762)
					(thickness 0.2286)
				)
			)
		)
		(property "Value" "0.1uF_25V_0402"
			(at 2.069035 2.567191 180)
			(unlocked yes)
			(layer "F.SilkS")
			(hide yes)
			(effects
				(font
					(size 0.762 0.762)
					(thickness 0.2286)
				)
			)
		)
		(sheetname "01-USER_IO")
		(sheetfile "01-USER_IO.kicad_sch")
		(duplicate_pad_numbers_are_jumpers no)
		(fp_line
			(start 0.65607 0.7)
			(end -0.65606 0.7)
			(stroke
				(width 0.2)
				(type solid)
			)
			(layer "F.SilkS")
		)
		(fp_line
			(start 0.65607 -0.7)
			(end -0.65606 -0.7)
			(stroke
				(width 0.2)
				(type solid)
			)
			(layer "F.SilkS")
		)
		(fp_line
			(start 0.75607 0.4)
			(end -0.75606 0.4)
			(stroke
				(width 0.2)
				(type solid)
			)
			(layer "F.CrtYd")
		)
		(fp_line
			(start 0.75607 -0.4)
			(end 0.75607 0.4)
			(stroke
				(width 0.2)
				(type solid)
			)
			(layer "F.CrtYd")
		)
		(fp_line
			(start 0.75607 -0.4)
			(end -0.75606 -0.4)
			(stroke
				(width 0.2)
				(type solid)
			)
			(layer "F.CrtYd")
		)
		(fp_line
			(start -0.75606 -0.4)
			(end -0.75606 0.4)
			(stroke
				(width 0.2)
				(type solid)
			)
			(layer "F.CrtYd")
		)
		(fp_line
			(start 0.75607 0.4)
			(end -0.75606 0.4)
			(stroke
				(width 0.2)
				(type solid)
			)
			(layer "F.Fab")
		)
		(fp_line
			(start 0.75607 -0.4)
			(end 0.75607 0.4)
			(stroke
				(width 0.2)
				(type solid)
			)
			(layer "F.Fab")
		)
		(fp_line
			(start 0.75607 -0.4)
			(end -0.75606 -0.4)
			(stroke
				(width 0.2)
				(type solid)
			)
			(layer "F.Fab")
		)
		(fp_line
			(start 0.5 0)
			(end -0.5 0)
			(stroke
				(width 0.1)
				(type solid)
			)
			(layer "F.Fab")
		)
		(fp_line
			(start 0 -0.5)
			(end 0 0.5)
			(stroke
				(width 0.1)
				(type solid)
			)
			(layer "F.Fab")
		)
		(fp_line
			(start -0.75606 -0.4)
			(end -0.75606 0.4)
			(stroke
				(width 0.2)
				(type solid)
			)
			(layer "F.Fab")
		)
		(fp_text user "${REFERENCE}"
			(at -0.00001 0.09601 180)
			(unlocked yes)
			(layer "F.Fab")
			(effects
				(font
					(face "Arial")
					(size 0.63 0.63)
					(thickness 0.1)
				)
				(justify left bottom)
			)
		)
		(pad "1" smd rect
			(at -0.36553 0 180)
			(size 0.58106 0.51213)
			(layers "F.Cu" "F.Mask" "F.Paste")
			(net "+3.3V")
			(solder_mask_margin 0)
			(solder_paste_margin 0)
		)
		(pad "2" smd rect
			(at 0.36554 0 180)
			(size 0.58106 0.51213)
			(layers "F.Cu" "F.Mask" "F.Paste")
			(net "GND")
			(solder_mask_margin 0)
			(solder_paste_margin 0)
		)
	)
)
